(kicad_pcb
	(version 20241229)
	(generator "pcbnew")
	(generator_version "9.0")
	(general
		(thickness 1.599998)
		(legacy_teardrops no)
	)
	(paper "A4")
	(title_block
		(title "Artix - Datacenter Secure Control Module (DC-SCM)")
		(date "2024-11-06")
		(rev "1.1.3")
		(comment 9 "footprints 245-250 of 544")
	)
	(layers
		(0 "F.Cu" signal)
		(4 "In1.Cu" signal)
		(6 "In2.Cu" signal)
		(8 "In3.Cu" signal)
		(10 "In4.Cu" signal)
		(12 "In5.Cu" signal)
		(14 "In6.Cu" signal)
		(2 "B.Cu" signal)
		(9 "F.Adhes" user "F.Adhesive")
		(11 "B.Adhes" user "B.Adhesive")
		(13 "F.Paste" user)
		(15 "B.Paste" user)
		(5 "F.SilkS" user "F.Silkscreen")
		(7 "B.SilkS" user "B.Silkscreen")
		(1 "F.Mask" user)
		(3 "B.Mask" user)
		(17 "Dwgs.User" user "User.Drawings")
		(19 "Cmts.User" user "User.Comments")
		(21 "Eco1.User" user "User.Eco1")
		(23 "Eco2.User" user "User.Eco2")
		(25 "Edge.Cuts" user)
		(27 "Margin" user)
		(31 "F.CrtYd" user "F.Courtyard")
		(29 "B.CrtYd" user "B.Courtyard")
		(35 "F.Fab" user)
		(33 "B.Fab" user)
	)
	(footprint "antmicro-footprints:C_0402_1005Metric"
		(layer "F.Cu")
		(at 135.35 101.8125 90)
		(descr "Capacitor SMD 0402")
		(tags "capacitor SMD 0402")
		(property "Reference" "C172"
			(at -3.6875 0.35 90)
			(layer "F.SilkS")
			(effects
				(font
					(size 0.7 0.7)
					(thickness 0.15)
				)
				(justify left bottom)
			)
		)
		(property "Value" "C_100n_0402"
			(at 0 1.4 90)
			(layer "F.Fab")
			(effects
				(font
					(size 0.7 0.7)
					(thickness 0.15)
				)
				(justify left bottom)
			)
		)
		(property "Datasheet" "https://www.murata.com/products/productdetail?partno=GRM155R61H104KE14%23"
			(at 0 0 90)
			(layer "F.Fab")
			(hide yes)
			(effects
				(font
					(size 1.27 1.27)
					(thickness 0.15)
				)
			)
		)
		(property "Description" "SMD Multilayer Ceramic Capacitor, 0.1 µF, 50 V, 0402 [1005 Metric], ± 10%, X5R, GRM Series"
			(at 0 0 90)
			(layer "F.Fab")
			(hide yes)
			(effects
				(font
					(size 1.27 1.27)
					(thickness 0.15)
				)
			)
		)
		(property "Author" "Antmicro"
			(at 237.1625 -33.5375 0)
			(layer "F.Fab")
			(hide yes)
			(effects
				(font
					(size 1 1)
					(thickness 0.15)
				)
			)
		)
		(property "Dielectric" "X5R"
			(at 237.1625 -33.5375 0)
			(layer "F.Fab")
			(hide yes)
			(effects
				(font
					(size 1 1)
					(thickness 0.15)
				)
			)
		)
		(property "License" "Apache-2.0"
			(at 237.1625 -33.5375 0)
			(layer "F.Fab")
			(hide yes)
			(effects
				(font
					(size 1 1)
					(thickness 0.15)
				)
			)
		)
		(property "MPN" "GRM155R61H104KE14D"
			(at 237.1625 -33.5375 0)
			(layer "F.Fab")
			(hide yes)
			(effects
				(font
					(size 1 1)
					(thickness 0.15)
				)
			)
		)
		(property "Manufacturer" "Murata"
			(at 237.1625 -33.5375 0)
			(layer "F.Fab")
			(hide yes)
			(effects
				(font
					(size 1 1)
					(thickness 0.15)
				)
			)
		)
		(property "Val" "100n"
			(at 237.1625 -33.5375 0)
			(layer "F.Fab")
			(hide yes)
			(effects
				(font
					(size 1 1)
					(thickness 0.15)
				)
			)
		)
		(property "Voltage" "50V"
			(at 237.1625 -33.5375 0)
			(layer "F.Fab")
			(hide yes)
			(effects
				(font
					(size 1 1)
					(thickness 0.15)
				)
			)
		)
		(sheetname "/Interfaces/")
		(sheetfile "interfaces.kicad_sch")
		(attr smd)
		(fp_rect
			(start -0.925 -0.47)
			(end 0.925 0.47)
			(stroke
				(width 0.05)
				(type default)
			)
			(fill no)
			(layer "F.CrtYd")
		)
		(fp_line
			(start 0.504 -0.25)
			(end 0.504 0.248)
			(stroke
				(width 0.15)
				(type solid)
			)
			(layer "F.Fab")
		)
		(fp_line
			(start -0.494 -0.25)
			(end 0.504 -0.25)
			(stroke
				(width 0.15)
				(type solid)
			)
			(layer "F.Fab")
		)
		(fp_line
			(start 0.504 0.248)
			(end -0.494 0.248)
			(stroke
				(width 0.15)
				(type solid)
			)
			(layer "F.Fab")
		)
		(fp_line
			(start -0.494 0.248)
			(end -0.494 -0.25)
			(stroke
				(width 0.15)
				(type solid)
			)
			(layer "F.Fab")
		)
		(pad "1" smd roundrect
			(at -0.48 0 90)
			(size 0.59 0.64)
			(layers "F.Cu" "F.Mask" "F.Paste")
			(roundrect_rratio 0.25)
			(net 1 "GND")
			(pintype "passive")
		)
		(pad "2" smd roundrect
			(at 0.48 0 90)
			(size 0.59 0.64)
			(layers "F.Cu" "F.Mask" "F.Paste")
			(roundrect_rratio 0.25)
			(net 2 "VCC3V3")
			(pintype "passive")
		)
	)
	(footprint "antmicro-footprints:C_0402_1005Metric"
		(layer "F.Cu")
		(at 127.75 98.6125)
		(descr "Capacitor SMD 0402")
		(tags "capacitor SMD 0402")
		(property "Reference" "C173"
			(at -3.65 0.2875 0)
			(layer "F.SilkS")
			(effects
				(font
					(size 0.7 0.7)
					(thickness 0.15)
				)
				(justify left bottom)
			)
		)
		(property "Value" "C_100n_0402"
			(at 0 1.4 0)
			(layer "F.Fab")
			(effects
				(font
					(size 0.7 0.7)
					(thickness 0.15)
				)
				(justify left bottom)
			)
		)
		(property "Datasheet" "https://www.murata.com/products/productdetail?partno=GRM155R61H104KE14%23"
			(at 0 0 0)
			(layer "F.Fab")
			(hide yes)
			(effects
				(font
					(size 1.27 1.27)
					(thickness 0.15)
				)
			)
		)
		(property "Description" "SMD Multilayer Ceramic Capacitor, 0.1 µF, 50 V, 0402 [1005 Metric], ± 10%, X5R, GRM Series"
			(at 0 0 0)
			(layer "F.Fab")
			(hide yes)
			(effects
				(font
					(size 1.27 1.27)
					(thickness 0.15)
				)
			)
		)
		(property "Author" "Antmicro"
			(at 0 0 0)
			(layer "F.Fab")
			(hide yes)
			(effects
				(font
					(size 1 1)
					(thickness 0.15)
				)
			)
		)
		(property "Dielectric" "X5R"
			(at 0 0 0)
			(layer "F.Fab")
			(hide yes)
			(effects
				(font
					(size 1 1)
					(thickness 0.15)
				)
			)
		)
		(property "License" "Apache-2.0"
			(at 0 0 0)
			(layer "F.Fab")
			(hide yes)
			(effects
				(font
					(size 1 1)
					(thickness 0.15)
				)
			)
		)
		(property "MPN" "GRM155R61H104KE14D"
			(at 0 0 0)
			(layer "F.Fab")
			(hide yes)
			(effects
				(font
					(size 1 1)
					(thickness 0.15)
				)
			)
		)
		(property "Manufacturer" "Murata"
			(at 0 0 0)
			(layer "F.Fab")
			(hide yes)
			(effects
				(font
					(size 1 1)
					(thickness 0.15)
				)
			)
		)
		(property "Val" "100n"
			(at 0 0 0)
			(layer "F.Fab")
			(hide yes)
			(effects
				(font
					(size 1 1)
					(thickness 0.15)
				)
			)
		)
		(property "Voltage" "50V"
			(at 0 0 0)
			(layer "F.Fab")
			(hide yes)
			(effects
				(font
					(size 1 1)
					(thickness 0.15)
				)
			)
		)
		(sheetname "/Interfaces/")
		(sheetfile "interfaces.kicad_sch")
		(attr smd)
		(fp_rect
			(start -0.925 -0.47)
			(end 0.925 0.47)
			(stroke
				(width 0.05)
				(type default)
			)
			(fill no)
			(layer "F.CrtYd")
		)
		(fp_line
			(start -0.494 -0.25)
			(end 0.504 -0.25)
			(stroke
				(width 0.15)
				(type solid)
			)
			(layer "F.Fab")
		)
		(fp_line
			(start -0.494 0.248)
			(end -0.494 -0.25)
			(stroke
				(width 0.15)
				(type solid)
			)
			(layer "F.Fab")
		)
		(fp_line
			(start 0.504 -0.25)
			(end 0.504 0.248)
			(stroke
				(width 0.15)
				(type solid)
			)
			(layer "F.Fab")
		)
		(fp_line
			(start 0.504 0.248)
			(end -0.494 0.248)
			(stroke
				(width 0.15)
				(type solid)
			)
			(layer "F.Fab")
		)
		(pad "1" smd roundrect
			(at -0.48 0)
			(size 0.59 0.64)
			(layers "F.Cu" "F.Mask" "F.Paste")
			(roundrect_rratio 0.25)
			(net 1 "GND")
			(pintype "passive")
		)
		(pad "2" smd roundrect
			(at 0.48 0)
			(size 0.59 0.64)
			(layers "F.Cu" "F.Mask" "F.Paste")
			(roundrect_rratio 0.25)
			(net 2 "VCC3V3")
			(pintype "passive")
		)
	)
	(footprint "antmicro-footprints:C_0402_1005Metric"
		(layer "F.Cu")
		(at 127.45 94.1125)
		(descr "Capacitor SMD 0402")
		(tags "capacitor SMD 0402")
		(property "Reference" "C174"
			(at -3.65 0.3875 0)
			(layer "F.SilkS")
			(effects
				(font
					(size 0.7 0.7)
					(thickness 0.15)
				)
				(justify left bottom)
			)
		)
		(property "Value" "C_100n_0402"
			(at 0 1.4 0)
			(layer "F.Fab")
			(effects
				(font
					(size 0.7 0.7)
					(thickness 0.15)
				)
				(justify left bottom)
			)
		)
		(property "Datasheet" "https://www.murata.com/products/productdetail?partno=GRM155R61H104KE14%23"
			(at 0 0 0)
			(layer "F.Fab")
			(hide yes)
			(effects
				(font
					(size 1.27 1.27)
					(thickness 0.15)
				)
			)
		)
		(property "Description" "SMD Multilayer Ceramic Capacitor, 0.1 µF, 50 V, 0402 [1005 Metric], ± 10%, X5R, GRM Series"
			(at 0 0 0)
			(layer "F.Fab")
			(hide yes)
			(effects
				(font
					(size 1.27 1.27)
					(thickness 0.15)
				)
			)
		)
		(property "Author" "Antmicro"
			(at 0 0 0)
			(layer "F.Fab")
			(hide yes)
			(effects
				(font
					(size 1 1)
					(thickness 0.15)
				)
			)
		)
		(property "Dielectric" "X5R"
			(at 0 0 0)
			(layer "F.Fab")
			(hide yes)
			(effects
				(font
					(size 1 1)
					(thickness 0.15)
				)
			)
		)
		(property "License" "Apache-2.0"
			(at 0 0 0)
			(layer "F.Fab")
			(hide yes)
			(effects
				(font
					(size 1 1)
					(thickness 0.15)
				)
			)
		)
		(property "MPN" "GRM155R61H104KE14D"
			(at 0 0 0)
			(layer "F.Fab")
			(hide yes)
			(effects
				(font
					(size 1 1)
					(thickness 0.15)
				)
			)
		)
		(property "Manufacturer" "Murata"
			(at 0 0 0)
			(layer "F.Fab")
			(hide yes)
			(effects
				(font
					(size 1 1)
					(thickness 0.15)
				)
			)
		)
		(property "Val" "100n"
			(at 0 0 0)
			(layer "F.Fab")
			(hide yes)
			(effects
				(font
					(size 1 1)
					(thickness 0.15)
				)
			)
		)
		(property "Voltage" "50V"
			(at 0 0 0)
			(layer "F.Fab")
			(hide yes)
			(effects
				(font
					(size 1 1)
					(thickness 0.15)
				)
			)
		)
		(sheetname "/Interfaces/")
		(sheetfile "interfaces.kicad_sch")
		(attr smd)
		(fp_rect
			(start -0.925 -0.47)
			(end 0.925 0.47)
			(stroke
				(width 0.05)
				(type default)
			)
			(fill no)
			(layer "F.CrtYd")
		)
		(fp_line
			(start -0.494 -0.25)
			(end 0.504 -0.25)
			(stroke
				(width 0.15)
				(type solid)
			)
			(layer "F.Fab")
		)
		(fp_line
			(start -0.494 0.248)
			(end -0.494 -0.25)
			(stroke
				(width 0.15)
				(type solid)
			)
			(layer "F.Fab")
		)
		(fp_line
			(start 0.504 -0.25)
			(end 0.504 0.248)
			(stroke
				(width 0.15)
				(type solid)
			)
			(layer "F.Fab")
		)
		(fp_line
			(start 0.504 0.248)
			(end -0.494 0.248)
			(stroke
				(width 0.15)
				(type solid)
			)
			(layer "F.Fab")
		)
		(pad "1" smd roundrect
			(at -0.48 0)
			(size 0.59 0.64)
			(layers "F.Cu" "F.Mask" "F.Paste")
			(roundrect_rratio 0.25)
			(net 1 "GND")
			(pintype "passive")
		)
		(pad "2" smd roundrect
			(at 0.48 0)
			(size 0.59 0.64)
			(layers "F.Cu" "F.Mask" "F.Paste")
			(roundrect_rratio 0.25)
			(net 2 "VCC3V3")
			(pintype "passive")
		)
	)
	(footprint "antmicro-footprints:SOT-723"
		(layer "F.Cu")
		(at 126.55 69.0125 -90)
		(property "Reference" "D15"
			(at 1.6875 -1.05 180)
			(layer "F.SilkS")
			(effects
				(font
					(size 0.7 0.7)
					(thickness 0.15)
				)
				(justify right bottom)
			)
		)
		(property "Value" "TPD2E009_SOT-9X3"
			(at 0 1.7 90)
			(layer "F.Fab")
			(effects
				(font
					(size 0.7 0.7)
					(thickness 0.15)
				)
				(justify right bottom)
			)
		)
		(property "Datasheet" "https://www.ti.com/lit/ds/symlink/tpd2e009.pdf?ts=1597910439511&ref_url=https%253A%252F%252Fwww.google.com%252F"
			(at 0 0 270)
			(layer "F.Fab")
			(hide yes)
			(effects
				(font
					(size 1.27 1.27)
					(thickness 0.15)
				)
			)
		)
		(property "Description" "TVS diode array, 8 kV, SOT-723, 5.5 V, 0.9 pF"
			(at 0 0 270)
			(layer "F.Fab")
			(hide yes)
			(effects
				(font
					(size 1.27 1.27)
					(thickness 0.15)
				)
			)
		)
		(property "Author" "Antmicro"
			(at 57.5375 195.5625 0)
			(layer "F.Fab")
			(hide yes)
			(effects
				(font
					(size 1 1)
					(thickness 0.15)
				)
			)
		)
		(property "License" "Apache-2.0"
			(at 57.5375 195.5625 0)
			(layer "F.Fab")
			(hide yes)
			(effects
				(font
					(size 1 1)
					(thickness 0.15)
				)
			)
		)
		(property "MPN" "TPD2E009DRTR"
			(at 57.5375 195.5625 0)
			(layer "F.Fab")
			(hide yes)
			(effects
				(font
					(size 1 1)
					(thickness 0.15)
				)
			)
		)
		(property "Manufacturer" "Texas Instruments"
			(at 57.5375 195.5625 0)
			(layer "F.Fab")
			(hide yes)
			(effects
				(font
					(size 1 1)
					(thickness 0.15)
				)
			)
		)
		(sheetname "/Interfaces/")
		(sheetfile "interfaces.kicad_sch")
		(attr smd)
		(fp_line
			(start 0.43 0.63)
			(end -0.22 0.63)
			(stroke
				(width 0.15)
				(type solid)
			)
			(layer "F.SilkS")
		)
		(fp_line
			(start 0.43 0.23)
			(end 0.43 0.63)
			(stroke
				(width 0.15)
				(type solid)
			)
			(layer "F.SilkS")
		)
		(fp_line
			(start -0.43 -0.1375)
			(end -0.43 0.1375)
			(stroke
				(width 0.15)
				(type solid)
			)
			(layer "F.SilkS")
		)
		(fp_line
			(start 0.43 -0.23)
			(end 0.43 -0.63)
			(stroke
				(width 0.15)
				(type solid)
			)
			(layer "F.SilkS")
		)
		(fp_line
			(start 0.43 -0.63)
			(end -0.2175 -0.63)
			(stroke
				(width 0.15)
				(type solid)
			)
			(layer "F.SilkS")
		)
		(fp_rect
			(start -0.83 -0.83)
			(end 0.83 0.83)
			(stroke
				(width 0.05)
				(type solid)
			)
			(fill no)
			(layer "F.CrtYd")
		)
		(fp_line
			(start 0.424 0.524)
			(end -0.424 0.524)
			(stroke
				(width 0.15)
				(type solid)
			)
			(layer "F.Fab")
		)
		(fp_line
			(start 0.424 -0.528)
			(end 0.424 0.524)
			(stroke
				(width 0.15)
				(type solid)
			)
			(layer "F.Fab")
		)
		(fp_line
			(start -0.09 -0.53)
			(end -0.43 -0.19)
			(stroke
				(width 0.15)
				(type solid)
			)
			(layer "F.Fab")
		)
		(fp_rect
			(start 0.424 0.524)
			(end -0.43 -0.528)
			(stroke
				(width 0.15)
				(type solid)
			)
			(fill no)
			(layer "F.Fab")
		)
		(pad "1" smd rect
			(at -0.501 -0.401 180)
			(size 0.3 0.4)
			(layers "F.Cu" "F.Mask" "F.Paste")
			(net 213 "/Interfaces/DBG_USB_D_N")
			(pinfunction "1")
			(pintype "passive")
		)
		(pad "2" smd rect
			(at -0.501 0.399 180)
			(size 0.3 0.4)
			(layers "F.Cu" "F.Mask" "F.Paste")
			(net 212 "/Interfaces/DBG_USB_D_P")
			(pinfunction "2")
			(pintype "passive")
		)
		(pad "3" smd rect
			(at 0.499 -0.001 180)
			(size 0.3 0.4)
			(layers "F.Cu" "F.Mask" "F.Paste")
			(net 1 "GND")
			(pinfunction "3")
			(pintype "passive")
		)
	)
	(footprint "antmicro-footprints:FB_0402_1005Metric"
		(layer "F.Cu")
		(at 131.45 88.7125 -90)
		(descr "Ferrite Bead SMD 0402")
		(tags "ferrite bead SMD 0402")
		(property "Reference" "FB1"
			(at -2.9125 -0.35 90)
			(layer "F.SilkS")
			(effects
				(font
					(size 0.7 0.7)
					(thickness 0.15)
				)
				(justify right bottom)
			)
		)
		(property "Value" "FB_600Z_0.3A_Murata-BLM15AG_0402"
			(at 0 1.4 90)
			(layer "F.Fab")
			(effects
				(font
					(size 0.7 0.7)
					(thickness 0.15)
				)
				(justify right bottom)
			)
		)
		(property "Datasheet" "https://www.murata.com/en-us/products/productdata/8796740059166/ENFA0018.pdf"
			(at 0 0 270)
			(layer "F.Fab")
			(hide yes)
			(effects
				(font
					(size 1.27 1.27)
					(thickness 0.15)
				)
			)
		)
		(property "Description" "Ferrite Bead, 0402 [1005 Metric], 600 ohm, 300 mA, BLM15AG_SN, 0.6 ohm, ± 25%, General use"
			(at 0 0 270)
			(layer "F.Fab")
			(hide yes)
			(effects
				(font
					(size 1.27 1.27)
					(thickness 0.15)
				)
			)
		)
		(property "Author" "Antmicro"
			(at 42.7375 220.1625 0)
			(layer "F.Fab")
			(hide yes)
			(effects
				(font
					(size 1 1)
					(thickness 0.15)
				)
			)
		)
		(property "Current" ""
			(at 42.7375 220.1625 0)
			(layer "F.Fab")
			(hide yes)
			(effects
				(font
					(size 1 1)
					(thickness 0.15)
				)
			)
		)
		(property "License" "Apache-2.0"
			(at 42.7375 220.1625 0)
			(layer "F.Fab")
			(hide yes)
			(effects
				(font
					(size 1 1)
					(thickness 0.15)
				)
			)
		)
		(property "MPN" "BLM15AG601SN1D"
			(at 42.7375 220.1625 0)
			(layer "F.Fab")
			(hide yes)
			(effects
				(font
					(size 1 1)
					(thickness 0.15)
				)
			)
		)
		(property "Manufacturer" "Murata"
			(at 42.7375 220.1625 0)
			(layer "F.Fab")
			(hide yes)
			(effects
				(font
					(size 1 1)
					(thickness 0.15)
				)
			)
		)
		(property "Val" "600Z/0.3A"
			(at 42.7375 220.1625 0)
			(layer "F.Fab")
			(hide yes)
			(effects
				(font
					(size 1 1)
					(thickness 0.15)
				)
			)
		)
		(sheetname "/Interfaces/")
		(sheetfile "interfaces.kicad_sch")
		(attr smd)
		(fp_rect
			(start -0.925 -0.47)
			(end 0.925 0.47)
			(stroke
				(width 0.05)
				(type default)
			)
			(fill no)
			(layer "F.CrtYd")
		)
		(fp_rect
			(start -0.5 -0.25)
			(end 0.5 0.25)
			(stroke
				(width 0.15)
				(type solid)
			)
			(fill no)
			(layer "F.Fab")
		)
		(pad "1" smd roundrect
			(at -0.48 0 270)
			(size 0.59 0.64)
			(layers "F.Cu" "F.Mask" "F.Paste")
			(roundrect_rratio 0.25)
			(net 2 "VCC3V3")
			(pintype "passive")
		)
		(pad "2" smd roundrect
			(at 0.48 0 270)
			(size 0.59 0.64)
			(layers "F.Cu" "F.Mask" "F.Paste")
			(roundrect_rratio 0.25)
			(net 116 "/Interfaces/FT_VPLL")
			(pintype "passive")
		)
	)
	(footprint "antmicro-footprints:R_0402_1005Metric"
		(layer "F.Cu")
		(at 135.85 89.0125 -90)
		(descr "Resistor SMD 0402")
		(tags "resistor SMD 0402")
		(property "Reference" "R3"
			(at -0.7125 -1.35 90)
			(layer "F.SilkS")
			(effects
				(font
					(size 0.7 0.7)
					(thickness 0.15)
				)
				(justify right bottom)
			)
		)
		(property "Value" "R_12k1_0402"
			(at 0 1.4 90)
			(layer "F.Fab")
			(effects
				(font
					(size 0.7 0.7)
					(thickness 0.15)
				)
				(justify right bottom)
			)
		)
		(property "Datasheet" "https://www.bourns.com/docs/product-datasheets/cr.pdf"
			(at 0 0 270)
			(layer "F.Fab")
			(hide yes)
			(effects
				(font
					(size 1.27 1.27)
					(thickness 0.15)
				)
			)
		)
		(property "Description" "SMD Chip Resistor, 12.1 kohm, ± 1%, 62.5 mW, 0402 [1005 Metric], Thick Film, General Purpose"
			(at 0 0 270)
			(layer "F.Fab")
			(hide yes)
			(effects
				(font
					(size 1.27 1.27)
					(thickness 0.15)
				)
			)
		)
		(property "Author" "Antmicro"
			(at 46.8375 224.8625 0)
			(layer "F.Fab")
			(hide yes)
			(effects
				(font
					(size 1 1)
					(thickness 0.15)
				)
			)
		)
		(property "License" "Apache-2.0"
			(at 46.8375 224.8625 0)
			(layer "F.Fab")
			(hide yes)
			(effects
				(font
					(size 1 1)
					(thickness 0.15)
				)
			)
		)
		(property "MPN" "CR0402-FX-1212GLF"
			(at 46.8375 224.8625 0)
			(layer "F.Fab")
			(hide yes)
			(effects
				(font
					(size 1 1)
					(thickness 0.15)
				)
			)
		)
		(property "Manufacturer" "Bourns"
			(at 46.8375 224.8625 0)
			(layer "F.Fab")
			(hide yes)
			(effects
				(font
					(size 1 1)
					(thickness 0.15)
				)
			)
		)
		(property "Tolerance" "1%"
			(at 46.8375 224.8625 0)
			(layer "F.Fab")
			(hide yes)
			(effects
				(font
					(size 1 1)
					(thickness 0.15)
				)
			)
		)
		(property "Val" "12k1"
			(at 46.8375 224.8625 0)
			(layer "F.Fab")
			(hide yes)
			(effects
				(font
					(size 1 1)
					(thickness 0.15)
				)
			)
		)
		(sheetname "/Interfaces/")
		(sheetfile "interfaces.kicad_sch")
		(attr smd)
		(fp_rect
			(start -0.925 -0.47)
			(end 0.925 0.47)
			(stroke
				(width 0.05)
				(type default)
			)
			(fill no)
			(layer "F.CrtYd")
		)
		(fp_rect
			(start -0.5 -0.25)
			(end 0.5 0.25)
			(stroke
				(width 0.15)
				(type solid)
			)
			(fill no)
			(layer "F.Fab")
		)
		(pad "1" smd roundrect
			(at -0.48 0 270)
			(size 0.59 0.64)
			(layers "F.Cu" "F.Mask" "F.Paste")
			(roundrect_rratio 0.25)
			(net 1 "GND")
			(pintype "passive")
		)
		(pad "2" smd roundrect
			(at 0.48 0 270)
			(size 0.59 0.64)
			(layers "F.Cu" "F.Mask" "F.Paste")
			(roundrect_rratio 0.25)
			(net 298 "Net-(U19-REF)")
			(pintype "passive")
		)
	)
)
